(kicad_pcb
	(version 20260206)
	(generator "pcbnew")
	(generator_version "10.0")
	(general
		(thickness 1.6)
		(legacy_teardrops no)
	)
	(paper "A4")
	(title_block
		(title "Bryce Canyon_SCC_16316-1_OCP.brd")
		(comment 1 "Bryce Canyon / footprints 968-975 of 1561")
	)
	(layers
		(0 "F.Cu" signal "TOP")
		(4 "In1.Cu" signal "L2GND")
		(6 "In2.Cu" signal "L3")
		(8 "In3.Cu" signal "L4VCC")
		(10 "In4.Cu" signal "L5VCC")
		(12 "In5.Cu" signal "L6")
		(14 "In6.Cu" signal "L7GND")
		(2 "B.Cu" signal "BOTTOM")
		(9 "F.Adhes" user "F.Adhesive")
		(11 "B.Adhes" user "B.Adhesive")
		(13 "F.Paste" user "Package Geometry/Pastemask Top")
		(15 "B.Paste" user "Package Geometry/Pastemask Bottom")
		(5 "F.SilkS" user "Ref Des/Silkscreen Top")
		(7 "B.SilkS" user "Ref Des/Silkscreen Bottom")
		(1 "F.Mask" user "Board Geometry/Soldermask Top")
		(3 "B.Mask" user "Board Geometry/Soldermask Bottom")
		(17 "Dwgs.User" user "User.Drawings")
		(19 "Cmts.User" user "User.Comments")
		(21 "Eco1.User" user "User.Eco1")
		(23 "Eco2.User" user "User.Eco2")
		(25 "Edge.Cuts" user "Board Geometry/Outline")
		(27 "Margin" user)
		(31 "F.CrtYd" user "Package Geometry/Place Bound Top")
		(29 "B.CrtYd" user "Package Geometry/Place Bound Bottom")
		(35 "F.Fab" user "Ref Des/Assembly Top")
		(33 "B.Fab" user "Ref Des/Assembly Bottom")
	)
	(footprint ""
		(layer "B.Cu")
		(at 163.195 -59.6138 -90)
		(property "Reference" "C369"
			(at 0 0 90)
			(layer "B.SilkS")
			(hide yes)
			(effects
				(font
					(size 1.27 1.27)
				)
				(justify mirror)
			)
		)
		(property "Value" "SC1U16V2KX-7-GP"
			(at -1.7526 -1.6002 270)
			(unlocked yes)
			(layer "B.Fab")
			(hide yes)
			(effects
				(font
					(size 1.016 1.016)
					(thickness 0.1524)
				)
				(justify mirror)
			)
		)
		(property "Device Type" "C402-TO0D2H24"
			(at -1.7526 -3.1242 270)
			(unlocked yes)
			(layer "B.Fab")
			(hide yes)
			(effects
				(font
					(size 1.016 1.016)
					(thickness 0.1524)
				)
				(justify mirror)
			)
		)
		(duplicate_pad_numbers_are_jumpers no)
		(fp_rect
			(start 0.4826 0.889)
			(end -0.4826 -0.889)
			(stroke
				(width 0)
				(type default)
			)
			(fill no)
			(layer "B.CrtYd")
		)
		(fp_rect
			(start 0.4826 0.889)
			(end -0.4826 -0.889)
			(stroke
				(width 0)
				(type default)
			)
			(fill no)
			(layer "B.Fab")
		)
		(pad "1" smd custom
			(at 0 -0.4572 90)
			(size 0.1524 0.1524)
			(layers "B.Cu" "B.Mask" "B.Paste")
			(net "VDDA_SAS_REF_CLK")
			(options
				(clearance outline)
				(anchor circle)
			)
			(primitives
				(gr_poly
					(pts
						(arc
							(start -0.254 -0.3048)
							(mid -0.325842 -0.275042)
							(end -0.3556 -0.2032)
						)
						(arc
							(start -0.3556 0.2032)
							(mid -0.325842 0.275042)
							(end -0.254 0.3048)
						)
						(arc
							(start 0.254 0.3048)
							(mid 0.325842 0.275042)
							(end 0.3556 0.2032)
						)
						(arc
							(start 0.3556 -0.2032)
							(mid 0.325842 -0.275042)
							(end 0.254 -0.3048)
						)
					)
					(width 0)
					(fill yes)
				)
			)
		)
		(pad "2" smd custom
			(at 0 0.4572 90)
			(size 0.1524 0.1524)
			(layers "B.Cu" "B.Mask" "B.Paste")
			(net "GND")
			(options
				(clearance outline)
				(anchor circle)
			)
			(primitives
				(gr_poly
					(pts
						(arc
							(start -0.254 -0.3048)
							(mid -0.325842 -0.275042)
							(end -0.3556 -0.2032)
						)
						(arc
							(start -0.3556 0.2032)
							(mid -0.325842 0.275042)
							(end -0.254 0.3048)
						)
						(arc
							(start 0.254 0.3048)
							(mid 0.325842 0.275042)
							(end 0.3556 0.2032)
						)
						(arc
							(start 0.3556 -0.2032)
							(mid 0.325842 -0.275042)
							(end 0.254 -0.3048)
						)
					)
					(width 0)
					(fill yes)
				)
			)
		)
	)
	(footprint ""
		(layer "B.Cu")
		(at 116.3574 -71.882)
		(property "Reference" "C153"
			(at 0 0 0)
			(layer "B.SilkS")
			(hide yes)
			(effects
				(font
					(size 1.27 1.27)
				)
				(justify mirror)
			)
		)
		(property "Value" "SCD1U6D3V1KX-GP"
			(at 2.8321 -1.7399 0)
			(unlocked yes)
			(layer "B.Fab")
			(hide yes)
			(effects
				(font
					(size 1.016 1.016)
					(thickness 0.1524)
				)
				(justify mirror)
			)
		)
		(property "Device Type" "C0201H13"
			(at 2.8321 -3.2639 0)
			(unlocked yes)
			(layer "B.Fab")
			(hide yes)
			(effects
				(font
					(size 1.016 1.016)
					(thickness 0.1524)
				)
				(justify mirror)
			)
		)
		(duplicate_pad_numbers_are_jumpers no)
		(fp_rect
			(start 0.2794 0.6477)
			(end -0.2794 -0.6477)
			(stroke
				(width 0)
				(type default)
			)
			(fill no)
			(layer "B.CrtYd")
		)
		(fp_rect
			(start 0.2794 0.6477)
			(end -0.2794 -0.6477)
			(stroke
				(width 0)
				(type default)
			)
			(fill no)
			(layer "B.Fab")
		)
		(pad "1" smd custom
			(at 0 -0.2794 180)
			(size 0.0762 0.0762)
			(layers "B.Cu" "B.Mask" "B.Paste")
			(net "P1V8_E")
			(options
				(clearance outline)
				(anchor circle)
			)
			(primitives
				(gr_poly
					(pts
						(arc
							(start 0.1524 0.127)
							(mid 0.137521 0.162921)
							(end 0.1016 0.1778)
						)
						(arc
							(start -0.1016 0.1778)
							(mid -0.137521 0.162921)
							(end -0.1524 0.127)
						)
						(arc
							(start -0.1524 -0.127)
							(mid -0.137521 -0.162921)
							(end -0.1016 -0.1778)
						)
						(arc
							(start 0.1016 -0.1778)
							(mid 0.137521 -0.162921)
							(end 0.1524 -0.127)
						)
					)
					(width 0)
					(fill yes)
				)
			)
		)
		(pad "2" smd custom
			(at 0 0.2794 180)
			(size 0.0762 0.0762)
			(layers "B.Cu" "B.Mask" "B.Paste")
			(net "GND")
			(options
				(clearance outline)
				(anchor circle)
			)
			(primitives
				(gr_poly
					(pts
						(arc
							(start 0.1524 0.127)
							(mid 0.137521 0.162921)
							(end 0.1016 0.1778)
						)
						(arc
							(start -0.1016 0.1778)
							(mid -0.137521 0.162921)
							(end -0.1524 0.127)
						)
						(arc
							(start -0.1524 -0.127)
							(mid -0.137521 -0.162921)
							(end -0.1016 -0.1778)
						)
						(arc
							(start 0.1016 -0.1778)
							(mid 0.137521 -0.162921)
							(end 0.1524 -0.127)
						)
					)
					(width 0)
					(fill yes)
				)
			)
		)
	)
	(footprint ""
		(layer "B.Cu")
		(at 100.457 -59.4868)
		(property "Reference" "C132"
			(at 0 0 0)
			(layer "B.SilkS")
			(hide yes)
			(effects
				(font
					(size 1.27 1.27)
				)
				(justify mirror)
			)
		)
		(property "Value" "SCD1U6D3V1KX-GP"
			(at 2.8321 -1.7399 0)
			(unlocked yes)
			(layer "B.Fab")
			(hide yes)
			(effects
				(font
					(size 1.016 1.016)
					(thickness 0.1524)
				)
				(justify mirror)
			)
		)
		(property "Device Type" "C0201H13"
			(at 2.8321 -3.2639 0)
			(unlocked yes)
			(layer "B.Fab")
			(hide yes)
			(effects
				(font
					(size 1.016 1.016)
					(thickness 0.1524)
				)
				(justify mirror)
			)
		)
		(duplicate_pad_numbers_are_jumpers no)
		(fp_rect
			(start 0.2794 0.6477)
			(end -0.2794 -0.6477)
			(stroke
				(width 0)
				(type default)
			)
			(fill no)
			(layer "B.CrtYd")
		)
		(fp_rect
			(start 0.2794 0.6477)
			(end -0.2794 -0.6477)
			(stroke
				(width 0)
				(type default)
			)
			(fill no)
			(layer "B.Fab")
		)
		(pad "1" smd custom
			(at 0 -0.2794 180)
			(size 0.0762 0.0762)
			(layers "B.Cu" "B.Mask" "B.Paste")
			(net "P1V8_E")
			(options
				(clearance outline)
				(anchor circle)
			)
			(primitives
				(gr_poly
					(pts
						(arc
							(start 0.1524 0.127)
							(mid 0.137521 0.162921)
							(end 0.1016 0.1778)
						)
						(arc
							(start -0.1016 0.1778)
							(mid -0.137521 0.162921)
							(end -0.1524 0.127)
						)
						(arc
							(start -0.1524 -0.127)
							(mid -0.137521 -0.162921)
							(end -0.1016 -0.1778)
						)
						(arc
							(start 0.1016 -0.1778)
							(mid 0.137521 -0.162921)
							(end 0.1524 -0.127)
						)
					)
					(width 0)
					(fill yes)
				)
			)
		)
		(pad "2" smd custom
			(at 0 0.2794 180)
			(size 0.0762 0.0762)
			(layers "B.Cu" "B.Mask" "B.Paste")
			(net "GND")
			(options
				(clearance outline)
				(anchor circle)
			)
			(primitives
				(gr_poly
					(pts
						(arc
							(start 0.1524 0.127)
							(mid 0.137521 0.162921)
							(end 0.1016 0.1778)
						)
						(arc
							(start -0.1016 0.1778)
							(mid -0.137521 0.162921)
							(end -0.1524 0.127)
						)
						(arc
							(start -0.1524 -0.127)
							(mid -0.137521 -0.162921)
							(end -0.1016 -0.1778)
						)
						(arc
							(start 0.1016 -0.1778)
							(mid 0.137521 -0.162921)
							(end 0.1524 -0.127)
						)
					)
					(width 0)
					(fill yes)
				)
			)
		)
	)
	(footprint ""
		(layer "B.Cu")
		(at 177.923952 -48.210724 -90)
		(property "Reference" "C462"
			(at 0 0 90)
			(layer "B.SilkS")
			(hide yes)
			(effects
				(font
					(size 1.27 1.27)
				)
				(justify mirror)
			)
		)
		(property "Value" "SCD1U6D3V1KX-GP"
			(at 2.8321 -1.7399 270)
			(unlocked yes)
			(layer "B.Fab")
			(hide yes)
			(effects
				(font
					(size 1.016 1.016)
					(thickness 0.1524)
				)
				(justify mirror)
			)
		)
		(property "Device Type" "C0201H13"
			(at 2.8321 -3.2639 270)
			(unlocked yes)
			(layer "B.Fab")
			(hide yes)
			(effects
				(font
					(size 1.016 1.016)
					(thickness 0.1524)
				)
				(justify mirror)
			)
		)
		(duplicate_pad_numbers_are_jumpers no)
		(fp_rect
			(start 0.2794 0.6477)
			(end -0.2794 -0.6477)
			(stroke
				(width 0)
				(type default)
			)
			(fill no)
			(layer "B.CrtYd")
		)
		(fp_rect
			(start 0.2794 0.6477)
			(end -0.2794 -0.6477)
			(stroke
				(width 0)
				(type default)
			)
			(fill no)
			(layer "B.Fab")
		)
		(pad "1" smd custom
			(at 0 -0.2794 90)
			(size 0.0762 0.0762)
			(layers "B.Cu" "B.Mask" "B.Paste")
			(net "P1V8_C")
			(options
				(clearance outline)
				(anchor circle)
			)
			(primitives
				(gr_poly
					(pts
						(arc
							(start 0.1524 0.127)
							(mid 0.137521 0.162921)
							(end 0.1016 0.1778)
						)
						(arc
							(start -0.1016 0.1778)
							(mid -0.137521 0.162921)
							(end -0.1524 0.127)
						)
						(arc
							(start -0.1524 -0.127)
							(mid -0.137521 -0.162921)
							(end -0.1016 -0.1778)
						)
						(arc
							(start 0.1016 -0.1778)
							(mid 0.137521 -0.162921)
							(end 0.1524 -0.127)
						)
					)
					(width 0)
					(fill yes)
				)
			)
		)
		(pad "2" smd custom
			(at 0 0.2794 90)
			(size 0.0762 0.0762)
			(layers "B.Cu" "B.Mask" "B.Paste")
			(net "GND")
			(options
				(clearance outline)
				(anchor circle)
			)
			(primitives
				(gr_poly
					(pts
						(arc
							(start 0.1524 0.127)
							(mid 0.137521 0.162921)
							(end 0.1016 0.1778)
						)
						(arc
							(start -0.1016 0.1778)
							(mid -0.137521 0.162921)
							(end -0.1524 0.127)
						)
						(arc
							(start -0.1524 -0.127)
							(mid -0.137521 -0.162921)
							(end -0.1016 -0.1778)
						)
						(arc
							(start 0.1016 -0.1778)
							(mid 0.137521 -0.162921)
							(end 0.1524 -0.127)
						)
					)
					(width 0)
					(fill yes)
				)
			)
		)
	)
	(footprint ""
		(layer "B.Cu")
		(at 145.372582 -121.027952 90)
		(property "Reference" "R4"
			(at 0 0 90)
			(layer "B.SilkS")
			(hide yes)
			(effects
				(font
					(size 1.27 1.27)
				)
				(justify mirror)
			)
		)
		(property "Value" "4K53R2F-1-GP"
			(at -0.064008 -3.993896 90)
			(unlocked yes)
			(layer "B.Fab")
			(hide yes)
			(effects
				(font
					(size 1.016 1.016)
					(thickness 0.1524)
				)
				(justify mirror)
			)
		)
		(property "Device Type" "R402H16"
			(at -0.064008 -5.517896 90)
			(unlocked yes)
			(layer "B.Fab")
			(hide yes)
			(effects
				(font
					(size 1.016 1.016)
					(thickness 0.1524)
				)
				(justify mirror)
			)
		)
		(duplicate_pad_numbers_are_jumpers no)
		(fp_line
			(start 0.508 -0.9398)
			(end 0.508 0.9398)
			(stroke
				(width 0.1524)
				(type default)
			)
			(layer "B.SilkS")
		)
		(fp_line
			(start -0.508 -0.9398)
			(end 0.508 -0.9398)
			(stroke
				(width 0.1524)
				(type default)
			)
			(layer "B.SilkS")
		)
		(fp_rect
			(start 0.508 0.9398)
			(end -0.508 -0.9398)
			(stroke
				(width 0)
				(type default)
			)
			(fill no)
			(layer "B.CrtYd")
		)
		(fp_rect
			(start 0.508 0.9398)
			(end -0.508 -0.9398)
			(stroke
				(width 0)
				(type default)
			)
			(fill no)
			(layer "B.Fab")
		)
		(pad "1" smd custom
			(at 0 -0.4445 270)
			(size 0.1397 0.1397)
			(layers "B.Cu" "B.Mask" "B.Paste")
			(net "P1V8_C_PG_G")
			(options
				(clearance outline)
				(anchor circle)
			)
			(primitives
				(gr_poly
					(pts
						(arc
							(start -0.1778 0.2794)
							(mid -0.249642 0.249642)
							(end -0.2794 0.1778)
						)
						(arc
							(start -0.2794 -0.1778)
							(mid -0.249642 -0.249642)
							(end -0.1778 -0.2794)
						)
						(arc
							(start 0.1778 -0.2794)
							(mid 0.249642 -0.249642)
							(end 0.2794 -0.1778)
						)
						(arc
							(start 0.2794 0.1778)
							(mid 0.249642 0.249642)
							(end 0.1778 0.2794)
						)
					)
					(width 0)
					(fill yes)
				)
			)
		)
		(pad "2" smd custom
			(at 0 0.4445 270)
			(size 0.1397 0.1397)
			(layers "B.Cu" "B.Mask" "B.Paste")
			(net "P3V3")
			(options
				(clearance outline)
				(anchor circle)
			)
			(primitives
				(gr_poly
					(pts
						(arc
							(start -0.1778 0.2794)
							(mid -0.249642 0.249642)
							(end -0.2794 0.1778)
						)
						(arc
							(start -0.2794 -0.1778)
							(mid -0.249642 -0.249642)
							(end -0.1778 -0.2794)
						)
						(arc
							(start 0.1778 -0.2794)
							(mid 0.249642 -0.249642)
							(end 0.2794 -0.1778)
						)
						(arc
							(start 0.2794 0.1778)
							(mid 0.249642 0.249642)
							(end 0.1778 0.2794)
						)
					)
					(width 0)
					(fill yes)
				)
			)
		)
	)
	(footprint ""
		(layer "B.Cu")
		(at 111.379 -59.4487)
		(property "Reference" "C539"
			(at 0 0 0)
			(layer "B.SilkS")
			(hide yes)
			(effects
				(font
					(size 1.27 1.27)
				)
				(justify mirror)
			)
		)
		(property "Value" "SCD1U6D3V1KX-GP"
			(at 2.8321 -1.7399 0)
			(unlocked yes)
			(layer "B.Fab")
			(hide yes)
			(effects
				(font
					(size 1.016 1.016)
					(thickness 0.1524)
				)
				(justify mirror)
			)
		)
		(property "Device Type" "C0201H13"
			(at 2.8321 -3.2639 0)
			(unlocked yes)
			(layer "B.Fab")
			(hide yes)
			(effects
				(font
					(size 1.016 1.016)
					(thickness 0.1524)
				)
				(justify mirror)
			)
		)
		(duplicate_pad_numbers_are_jumpers no)
		(fp_rect
			(start 0.2794 0.6477)
			(end -0.2794 -0.6477)
			(stroke
				(width 0)
				(type default)
			)
			(fill no)
			(layer "B.CrtYd")
		)
		(fp_rect
			(start 0.2794 0.6477)
			(end -0.2794 -0.6477)
			(stroke
				(width 0)
				(type default)
			)
			(fill no)
			(layer "B.Fab")
		)
		(pad "1" smd custom
			(at 0 -0.2794 180)
			(size 0.0762 0.0762)
			(layers "B.Cu" "B.Mask" "B.Paste")
			(net "GB_VDDA")
			(options
				(clearance outline)
				(anchor circle)
			)
			(primitives
				(gr_poly
					(pts
						(arc
							(start 0.1524 0.127)
							(mid 0.137521 0.162921)
							(end 0.1016 0.1778)
						)
						(arc
							(start -0.1016 0.1778)
							(mid -0.137521 0.162921)
							(end -0.1524 0.127)
						)
						(arc
							(start -0.1524 -0.127)
							(mid -0.137521 -0.162921)
							(end -0.1016 -0.1778)
						)
						(arc
							(start 0.1016 -0.1778)
							(mid 0.137521 -0.162921)
							(end 0.1524 -0.127)
						)
					)
					(width 0)
					(fill yes)
				)
			)
		)
		(pad "2" smd custom
			(at 0 0.2794 180)
			(size 0.0762 0.0762)
			(layers "B.Cu" "B.Mask" "B.Paste")
			(net "GND")
			(options
				(clearance outline)
				(anchor circle)
			)
			(primitives
				(gr_poly
					(pts
						(arc
							(start 0.1524 0.127)
							(mid 0.137521 0.162921)
							(end 0.1016 0.1778)
						)
						(arc
							(start -0.1016 0.1778)
							(mid -0.137521 0.162921)
							(end -0.1524 0.127)
						)
						(arc
							(start -0.1524 -0.127)
							(mid -0.137521 -0.162921)
							(end -0.1016 -0.1778)
						)
						(arc
							(start 0.1016 -0.1778)
							(mid 0.137521 -0.162921)
							(end 0.1524 -0.127)
						)
					)
					(width 0)
					(fill yes)
				)
			)
		)
	)
	(footprint ""
		(layer "B.Cu")
		(at 127.0508 -49.4792 90)
		(property "Reference" "R115"
			(at 0 0 90)
			(layer "B.SilkS")
			(hide yes)
			(effects
				(font
					(size 1.27 1.27)
				)
				(justify mirror)
			)
		)
		(property "Value" "3K01R2F-3-GP"
			(at -0.064008 -3.993896 90)
			(unlocked yes)
			(layer "B.Fab")
			(hide yes)
			(effects
				(font
					(size 1.016 1.016)
					(thickness 0.1524)
				)
				(justify mirror)
			)
		)
		(property "Device Type" "R402H16"
			(at -0.064008 -5.517896 90)
			(unlocked yes)
			(layer "B.Fab")
			(hide yes)
			(effects
				(font
					(size 1.016 1.016)
					(thickness 0.1524)
				)
				(justify mirror)
			)
		)
		(duplicate_pad_numbers_are_jumpers no)
		(fp_line
			(start 0.508 -0.9398)
			(end 0.508 0.9398)
			(stroke
				(width 0.1524)
				(type default)
			)
			(layer "B.SilkS")
		)
		(fp_line
			(start -0.508 -0.9398)
			(end 0.508 -0.9398)
			(stroke
				(width 0.1524)
				(type default)
			)
			(layer "B.SilkS")
		)
		(fp_rect
			(start 0.508 0.9398)
			(end -0.508 -0.9398)
			(stroke
				(width 0)
				(type default)
			)
			(fill no)
			(layer "B.CrtYd")
		)
		(fp_rect
			(start 0.508 0.9398)
			(end -0.508 -0.9398)
			(stroke
				(width 0)
				(type default)
			)
			(fill no)
			(layer "B.Fab")
		)
		(pad "1" smd custom
			(at 0 -0.4445 270)
			(size 0.1397 0.1397)
			(layers "B.Cu" "B.Mask" "B.Paste")
			(net "RTRIM_A")
			(options
				(clearance outline)
				(anchor circle)
			)
			(primitives
				(gr_poly
					(pts
						(arc
							(start -0.1778 0.2794)
							(mid -0.249642 0.249642)
							(end -0.2794 0.1778)
						)
						(arc
							(start -0.2794 -0.1778)
							(mid -0.249642 -0.249642)
							(end -0.1778 -0.2794)
						)
						(arc
							(start 0.1778 -0.2794)
							(mid 0.249642 -0.249642)
							(end 0.2794 -0.1778)
						)
						(arc
							(start 0.2794 0.1778)
							(mid 0.249642 0.249642)
							(end 0.1778 0.2794)
						)
					)
					(width 0)
					(fill yes)
				)
			)
		)
		(pad "2" smd custom
			(at 0 0.4445 270)
			(size 0.1397 0.1397)
			(layers "B.Cu" "B.Mask" "B.Paste")
			(net "RTRIM_AN")
			(options
				(clearance outline)
				(anchor circle)
			)
			(primitives
				(gr_poly
					(pts
						(arc
							(start -0.1778 0.2794)
							(mid -0.249642 0.249642)
							(end -0.2794 0.1778)
						)
						(arc
							(start -0.2794 -0.1778)
							(mid -0.249642 -0.249642)
							(end -0.1778 -0.2794)
						)
						(arc
							(start 0.1778 -0.2794)
							(mid 0.249642 -0.249642)
							(end 0.2794 -0.1778)
						)
						(arc
							(start 0.2794 0.1778)
							(mid 0.249642 0.249642)
							(end 0.1778 0.2794)
						)
					)
					(width 0)
					(fill yes)
				)
			)
		)
	)
	(footprint ""
		(layer "B.Cu")
		(at 113.665 -70.3834 180)
		(property "Reference" "C163"
			(at 0 0 0)
			(layer "B.SilkS")
			(hide yes)
			(effects
				(font
					(size 1.27 1.27)
				)
				(justify mirror)
			)
		)
		(property "Value" "SCD1U6D3V1KX-GP"
			(at 2.8321 -1.7399 180)
			(unlocked yes)
			(layer "B.Fab")
			(hide yes)
			(effects
				(font
					(size 1.016 1.016)
					(thickness 0.1524)
				)
				(justify mirror)
			)
		)
		(property "Device Type" "C0201H13"
			(at 2.8321 -3.2639 180)
			(unlocked yes)
			(layer "B.Fab")
			(hide yes)
			(effects
				(font
					(size 1.016 1.016)
					(thickness 0.1524)
				)
				(justify mirror)
			)
		)
		(duplicate_pad_numbers_are_jumpers no)
		(fp_rect
			(start 0.2794 0.6477)
			(end -0.2794 -0.6477)
			(stroke
				(width 0)
				(type default)
			)
			(fill no)
			(layer "B.CrtYd")
		)
		(fp_rect
			(start 0.2794 0.6477)
			(end -0.2794 -0.6477)
			(stroke
				(width 0)
				(type default)
			)
			(fill no)
			(layer "B.Fab")
		)
		(pad "1" smd custom
			(at 0 -0.2794)
			(size 0.0762 0.0762)
			(layers "B.Cu" "B.Mask" "B.Paste")
			(net "P0V9")
			(options
				(clearance outline)
				(anchor circle)
			)
			(primitives
				(gr_poly
					(pts
						(arc
							(start 0.1524 0.127)
							(mid 0.137521 0.162921)
							(end 0.1016 0.1778)
						)
						(arc
							(start -0.1016 0.1778)
							(mid -0.137521 0.162921)
							(end -0.1524 0.127)
						)
						(arc
							(start -0.1524 -0.127)
							(mid -0.137521 -0.162921)
							(end -0.1016 -0.1778)
						)
						(arc
							(start 0.1016 -0.1778)
							(mid 0.137521 -0.162921)
							(end 0.1524 -0.127)
						)
					)
					(width 0)
					(fill yes)
				)
			)
		)
		(pad "2" smd custom
			(at 0 0.2794)
			(size 0.0762 0.0762)
			(layers "B.Cu" "B.Mask" "B.Paste")
			(net "GND")
			(options
				(clearance outline)
				(anchor circle)
			)
			(primitives
				(gr_poly
					(pts
						(arc
							(start 0.1524 0.127)
							(mid 0.137521 0.162921)
							(end 0.1016 0.1778)
						)
						(arc
							(start -0.1016 0.1778)
							(mid -0.137521 0.162921)
							(end -0.1524 0.127)
						)
						(arc
							(start -0.1524 -0.127)
							(mid -0.137521 -0.162921)
							(end -0.1016 -0.1778)
						)
						(arc
							(start 0.1016 -0.1778)
							(mid 0.137521 -0.162921)
							(end 0.1524 -0.127)
						)
					)
					(width 0)
					(fill yes)
				)
			)
		)
	)
)
